G04 #@! TF.GenerationSoftware,KiCad,Pcbnew,(5.0.1)-3*
G04 #@! TF.CreationDate,2019-04-10T15:36:06+02:00*
G04 #@! TF.ProjectId,discovery,646973636F766572792E6B696361645F,rev?*
G04 #@! TF.SameCoordinates,PX4c4640PY8a48028*
G04 #@! TF.FileFunction,Other,User*
%FSLAX46Y46*%
G04 Gerber Fmt 4.6, Leading zero omitted, Abs format (unit mm)*
%MOMM*%
%LPD*%
G01*
G04 APERTURE LIST*
G04 APERTURE END LIST*
M02*
